# BASEBOARD_FAB2 (Tioga Pass) — schematic netlist excerpt (pin names and nets, part order shuffled) for the footprints in the layout excerpt that follows; sources: Cadence DE-HDL packaged netlist, KiCad conversion of Wiwynn_Tioga_Pass_MB.brd

R7D43  RES  0.0 5% EMPTY  pkg 0402  page 93 : A = FM_CPU1_PROCHOT_LVT3_K_N ; B = H_CPU1_PROCHOT_G_PCH_N
U8D2  TTL1G07_A  74LVC1G07 IC  pkg SOP  page 157 : A = PWRGD_DSW_PWROK ; Y = RST_BMC_SRST_R2_N
C9P12  CAP_A  0.1UF 16V 10% EMPTY  pkg 0402V  page 199 : A = A_HSC_VOUT ; B = AGND_HSC

(kicad_pcb
	(version 20260206)
	(generator "pcbnew")
	(generator_version "10.0")
	(general
		(thickness 1.6)
		(legacy_teardrops no)
	)
	(paper "A4")
	(title_block
		(title "Wiwynn_Tioga_Pass_MB.brd")
		(comment 1 "Tioga Pass / footprints 3777-3779 of 4770")
	)
	(layers
		(0 "F.Cu" signal "TOP")
		(4 "In1.Cu" signal "L2GND")
		(6 "In2.Cu" signal "L3")
		(8 "In3.Cu" signal "L4GND")
		(10 "In4.Cu" signal "L5")
		(12 "In5.Cu" signal "L6GND")
		(14 "In6.Cu" signal "L7VCC")
		(16 "In7.Cu" signal "L8VCC")
		(18 "In8.Cu" signal "L9GND")
		(20 "In9.Cu" signal "L10")
		(22 "In10.Cu" signal "L11GND")
		(24 "In11.Cu" signal "L12")
		(26 "In12.Cu" signal "L13GND")
		(2 "B.Cu" signal "BOTTOM")
		(9 "F.Adhes" user "F.Adhesive")
		(11 "B.Adhes" user "B.Adhesive")
		(13 "F.Paste" user "Package Geometry/Pastemask Top")
		(15 "B.Paste" user "Package Geometry/Pastemask Bottom")
		(5 "F.SilkS" user "Ref Des/Silkscreen Top")
		(7 "B.SilkS" user "Ref Des/Silkscreen Bottom")
		(1 "F.Mask" user "Board Geometry/Soldermask Top")
		(3 "B.Mask" user "Board Geometry/Soldermask Bottom")
		(17 "Dwgs.User" user "User.Drawings")
		(19 "Cmts.User" user "User.Comments")
		(21 "Eco1.User" user "User.Eco1")
		(23 "Eco2.User" user "User.Eco2")
		(25 "Edge.Cuts" user "Board Geometry/Outline")
		(27 "Margin" user)
		(31 "F.CrtYd" user "Package Geometry/Place Bound Top")
		(29 "B.CrtYd" user "Package Geometry/Place Bound Bottom")
		(35 "F.Fab" user "Ref Des/Assembly Top")
		(33 "B.Fab" user "Ref Des/Assembly Bottom")
	)
	(footprint ""
		(layer "B.Cu")
		(at 15.75308 -76.37272 90)
		(property "Reference" "C9P12"
			(at 0 0 90)
			(layer "B.SilkS")
			(hide yes)
			(effects
				(font
					(size 1.27 1.27)
				)
				(justify mirror)
			)
		)
		(property "Value" ""
			(at 0 0 90)
			(layer "B.Fab")
			(effects
				(font
					(size 1.27 1.27)
				)
				(justify mirror)
			)
		)
		(duplicate_pad_numbers_are_jumpers no)
		(fp_rect
			(start -0.3048 -0.1016)
			(end 0.3048 0.9906)
			(stroke
				(width 0)
				(type default)
			)
			(fill no)
			(layer "B.CrtYd")
		)
		(fp_line
			(start 0.3048 -0.1016)
			(end 0.3048 0.9906)
			(stroke
				(width 0.1)
				(type default)
			)
			(layer "B.Fab")
		)
		(fp_line
			(start -0.3048 -0.1016)
			(end 0.3048 -0.1016)
			(stroke
				(width 0.1)
				(type default)
			)
			(layer "B.Fab")
		)
		(fp_line
			(start 0.3048 0.9906)
			(end -0.3048 0.9906)
			(stroke
				(width 0.1)
				(type default)
			)
			(layer "B.Fab")
		)
		(fp_line
			(start -0.3048 0.9906)
			(end -0.3048 -0.1016)
			(stroke
				(width 0.1)
				(type default)
			)
			(layer "B.Fab")
		)
		(pad "1" smd rect
			(at 0 0 270)
			(size 0.508 0.508)
			(layers "B.Cu" "B.Mask" "B.Paste")
			(net "A_HSC_VOUT")
		)
		(pad "2" smd rect
			(at 0 0.889 270)
			(size 0.508 0.508)
			(layers "B.Cu" "B.Mask" "B.Paste")
			(net "AGND_HSC")
		)
		(zone
			(layer "B.Cu")
			(hatch none 0.5)
			(connect_pads
				(clearance 0)
			)
			(min_thickness 0.25)
			(keepout
				(tracks allowed)
				(vias not_allowed)
				(pads allowed)
				(copperpour not_allowed)
				(footprints allowed)
			)
			(placement
				(enabled no)
				(sheetname "")
			)
			(fill
				(thermal_gap 0.5)
				(thermal_bridge_width 0.5)
				(island_removal_mode 0)
			)
			(polygon
				(pts
					(xy 16.00708 -76.11872) (xy 16.38808 -76.11872) (xy 16.38808 -76.62672) (xy 16.00708 -76.62672)
				)
			)
		)
		(zone
			(layer "B.Cu")
			(hatch none 0.5)
			(connect_pads
				(clearance 0)
			)
			(min_thickness 0.25)
			(keepout
				(tracks not_allowed)
				(vias allowed)
				(pads allowed)
				(copperpour not_allowed)
				(footprints allowed)
			)
			(placement
				(enabled no)
				(sheetname "")
			)
			(fill
				(thermal_gap 0.5)
				(thermal_bridge_width 0.5)
				(island_removal_mode 0)
			)
			(polygon
				(pts
					(xy 16.00708 -76.11872) (xy 16.38808 -76.11872) (xy 16.38808 -76.62672) (xy 16.00708 -76.62672)
				)
			)
		)
	)
	(footprint ""
		(layer "B.Cu")
		(at 361.444794 -46.496986 -90)
		(property "Reference" "R7D43"
			(at 0 0 90)
			(layer "B.SilkS")
			(hide yes)
			(effects
				(font
					(size 1.27 1.27)
				)
				(justify mirror)
			)
		)
		(property "Value" ""
			(at 0 0 90)
			(layer "B.Fab")
			(effects
				(font
					(size 1.27 1.27)
				)
				(justify mirror)
			)
		)
		(duplicate_pad_numbers_are_jumpers no)
		(fp_poly
			(pts
				(xy 0.2794 -0.1016) (xy -0.2794 -0.1016) (xy -0.2794 0.9906) (xy 0.2794 0.9906)
			)
			(stroke
				(width 0)
				(type default)
			)
			(fill no)
			(layer "B.CrtYd")
		)
		(fp_line
			(start -0.2794 0.9906)
			(end -0.2794 -0.1016)
			(stroke
				(width 0.1)
				(type default)
			)
			(layer "B.Fab")
		)
		(fp_line
			(start 0.2794 0.9906)
			(end -0.2794 0.9906)
			(stroke
				(width 0.1)
				(type default)
			)
			(layer "B.Fab")
		)
		(fp_line
			(start -0.2794 -0.1016)
			(end 0.2794 -0.1016)
			(stroke
				(width 0.1)
				(type default)
			)
			(layer "B.Fab")
		)
		(fp_line
			(start 0.2794 -0.1016)
			(end 0.2794 0.9906)
			(stroke
				(width 0.1)
				(type default)
			)
			(layer "B.Fab")
		)
		(pad "1" smd rect
			(at 0 0 90)
			(size 0.508 0.508)
			(layers "B.Cu" "B.Mask" "B.Paste")
			(net "FM_CPU1_PROCHOT_LVT3_K_N")
		)
		(pad "2" smd rect
			(at 0 0.889 90)
			(size 0.508 0.508)
			(layers "B.Cu" "B.Mask" "B.Paste")
			(net "H_CPU1_PROCHOT_G_PCH_N")
		)
		(zone
			(layer "B.Cu")
			(hatch none 0.5)
			(connect_pads
				(clearance 0)
			)
			(min_thickness 0.25)
			(keepout
				(tracks not_allowed)
				(vias allowed)
				(pads allowed)
				(copperpour not_allowed)
				(footprints allowed)
			)
			(placement
				(enabled no)
				(sheetname "")
			)
			(fill
				(thermal_gap 0.5)
				(thermal_bridge_width 0.5)
				(island_removal_mode 0)
			)
			(polygon
				(pts
					(xy 360.809794 -46.242986) (xy 360.809794 -46.750986) (xy 361.190794 -46.750986) (xy 361.190794 -46.242986)
				)
			)
		)
		(zone
			(layer "B.Cu")
			(hatch none 0.5)
			(connect_pads
				(clearance 0)
			)
			(min_thickness 0.25)
			(keepout
				(tracks allowed)
				(vias not_allowed)
				(pads allowed)
				(copperpour not_allowed)
				(footprints allowed)
			)
			(placement
				(enabled no)
				(sheetname "")
			)
			(fill
				(thermal_gap 0.5)
				(thermal_bridge_width 0.5)
				(island_removal_mode 0)
			)
			(polygon
				(pts
					(xy 361.190794 -46.242986) (xy 361.190794 -46.750986) (xy 360.809794 -46.750986) (xy 360.809794 -46.242986)
				)
			)
		)
	)
	(footprint ""
		(layer "B.Cu")
		(at 454.740772 -35.174174 90)
		(property "Reference" "U8D2"
			(at 0.508 1.92913 270)
			(unlocked yes)
			(layer "B.SilkS")
			(effects
				(font
					(size 0.7874 0.5842)
					(thickness 0.1524)
				)
				(justify left mirror)
			)
		)
		(property "Value" ""
			(at 0 0 90)
			(layer "B.Fab")
			(effects
				(font
					(size 1.27 1.27)
				)
				(justify mirror)
			)
		)
		(duplicate_pad_numbers_are_jumpers no)
		(fp_circle
			(center 0.4699 -0.8382)
			(end 0.4699 -0.7112)
			(stroke
				(width 0.254)
				(type default)
			)
			(fill no)
			(layer "B.SilkS")
		)
		(fp_poly
			(pts
				(xy -0.21463 -0.450088) (xy -1.56337 -0.450088) (xy -1.56337 1.75006) (xy -0.21463 1.75006)
			)
			(stroke
				(width 0)
				(type default)
			)
			(fill no)
			(layer "B.CrtYd")
		)
		(fp_line
			(start -0.21463 -0.450088)
			(end -1.56337 -0.450088)
			(stroke
				(width 0.1)
				(type default)
			)
			(layer "B.Fab")
		)
		(fp_line
			(start -1.56337 -0.450088)
			(end -1.56337 1.75006)
			(stroke
				(width 0.1)
				(type default)
			)
			(layer "B.Fab")
		)
		(fp_line
			(start -0.21463 1.75006)
			(end -0.21463 -0.450088)
			(stroke
				(width 0.1)
				(type default)
			)
			(layer "B.Fab")
		)
		(fp_line
			(start -1.56337 1.75006)
			(end -0.21463 1.75006)
			(stroke
				(width 0.1)
				(type default)
			)
			(layer "B.Fab")
		)
		(fp_circle
			(center 0.4699 -0.8382)
			(end 0.4699 -0.7112)
			(stroke
				(width 0.254)
				(type default)
			)
			(fill no)
			(layer "B.Fab")
		)
		(pad "1" smd rect
			(at 0 0 270)
			(size 1.016 0.381)
			(layers "B.Cu" "B.Mask" "B.Paste")
			(net "Net_6477")
		)
		(pad "2" smd rect
			(at 0 0.649986 270)
			(size 1.016 0.381)
			(layers "B.Cu" "B.Mask" "B.Paste")
			(net "PWRGD_DSW_PWROK")
		)
		(pad "3" smd rect
			(at 0 1.299972 270)
			(size 1.016 0.381)
			(layers "B.Cu" "B.Mask" "B.Paste")
			(net "GND")
		)
		(pad "4" smd rect
			(at -1.778 1.299972 270)
			(size 1.016 0.381)
			(layers "B.Cu" "B.Mask" "B.Paste")
			(net "RST_BMC_SRST_R2_N")
		)
		(pad "5" smd rect
			(at -1.778 0 270)
			(size 1.016 0.381)
			(layers "B.Cu" "B.Mask" "B.Paste")
			(net "P3V3_STBY")
		)
	)
)
